(kicad_pcb
	(version 20241229)
	(generator "pcbnew")
	(generator_version "9.0")
	(general
		(thickness 1.6296)
		(legacy_teardrops no)
	)
	(paper "A3")
	(title_block
		(title "Thunderbolt to 10GbE adapter")
		(date "2026-04-21")
		(rev "1.1.0")
		(company "Antmicro Ltd")
		(comment 1 "www.antmicro.com")
		(comment 9 "footprints 258-261 of 703")
	)
	(layers
		(0 "F.Cu" signal)
		(4 "In1.Cu" signal)
		(6 "In2.Cu" signal)
		(8 "In3.Cu" signal)
		(10 "In4.Cu" signal)
		(12 "In5.Cu" signal)
		(14 "In6.Cu" signal)
		(2 "B.Cu" signal)
		(9 "F.Adhes" user "F.Adhesive")
		(11 "B.Adhes" user "B.Adhesive")
		(13 "F.Paste" user)
		(15 "B.Paste" user)
		(5 "F.SilkS" user "F.Silkscreen")
		(7 "B.SilkS" user "B.Silkscreen")
		(1 "F.Mask" user)
		(3 "B.Mask" user)
		(17 "Dwgs.User" user "User.Drawings")
		(19 "Cmts.User" user "User.Comments")
		(21 "Eco1.User" user "User.Eco1")
		(23 "Eco2.User" user "User.Eco2")
		(25 "Edge.Cuts" user)
		(27 "Margin" user)
		(31 "F.CrtYd" user "F.Courtyard")
		(29 "B.CrtYd" user "B.Courtyard")
		(35 "F.Fab" user)
		(33 "B.Fab" user)
	)
	(footprint "antmicro-footprints:C_0603_1608Metric_EIA"
		(layer "F.Cu")
		(at 134.505 99.774998 -90)
		(descr "Capacitor SMD 0603, IPC-7351 Density Level A")
		(tags "Capacitor 0603")
		(property "Reference" "C247"
			(at -9.274999 -37.745 270)
			(layer "F.SilkS")
			(effects
				(font
					(size 0.7 0.7)
					(thickness 0.15)
				)
			)
		)
		(property "Value" "C_22u_16V_0603"
			(at -1.42757 1.770288 270)
			(layer "F.Fab")
			(effects
				(font
					(size 0.7 0.7)
					(thickness 0.15)
				)
				(justify left bottom)
			)
		)
		(property "Datasheet" "https://product.samsungsem.com/mlcc/CL10A226MO7JZN.do"
			(at 0 0 270)
			(layer "F.Fab")
			(hide yes)
			(effects
				(font
					(size 1.27 1.27)
					(thickness 0.15)
				)
			)
		)
		(property "Description" "SMD Multilayer Ceramic Capacitor"
			(at 0 0 270)
			(layer "F.Fab")
			(hide yes)
			(effects
				(font
					(size 1.27 1.27)
					(thickness 0.15)
				)
			)
		)
		(property "MPN" "CL10A226MO7JZNC"
			(at 0 0 270)
			(unlocked yes)
			(layer "F.Fab")
			(hide yes)
			(effects
				(font
					(size 1 1)
					(thickness 0.15)
				)
			)
		)
		(property "Manufacturer" "Samsung Electro-Mechanics"
			(at 0 0 270)
			(unlocked yes)
			(layer "F.Fab")
			(hide yes)
			(effects
				(font
					(size 1 1)
					(thickness 0.15)
				)
			)
		)
		(property "License" "Apache-2.0"
			(at 0 0 270)
			(unlocked yes)
			(layer "F.Fab")
			(hide yes)
			(effects
				(font
					(size 1 1)
					(thickness 0.15)
				)
			)
		)
		(property "Author" "Antmicro"
			(at 0 0 270)
			(unlocked yes)
			(layer "F.Fab")
			(hide yes)
			(effects
				(font
					(size 1 1)
					(thickness 0.15)
				)
			)
		)
		(property "Val" "22u"
			(at 0 0 270)
			(unlocked yes)
			(layer "F.Fab")
			(hide yes)
			(effects
				(font
					(size 1 1)
					(thickness 0.15)
				)
			)
		)
		(property "Voltage" "16V"
			(at 0 0 270)
			(unlocked yes)
			(layer "F.Fab")
			(hide yes)
			(effects
				(font
					(size 1 1)
					(thickness 0.15)
				)
			)
		)
		(property "Dielectric" ""
			(at 0 0 270)
			(unlocked yes)
			(layer "F.Fab")
			(hide yes)
			(effects
				(font
					(size 1 1)
					(thickness 0.15)
				)
			)
		)
		(sheetname "/X710-AT2 power/")
		(sheetfile "x710-at2-power.kicad_sch")
		(attr smd)
		(fp_line
			(start -0.15 0.55)
			(end 0.15 0.55)
			(stroke
				(width 0.15)
				(type solid)
			)
			(layer "F.SilkS")
		)
		(fp_line
			(start -0.15 -0.55)
			(end 0.15 -0.55)
			(stroke
				(width 0.15)
				(type solid)
			)
			(layer "F.SilkS")
		)
		(fp_rect
			(start -1.25 -0.65)
			(end 1.25 0.65)
			(stroke
				(width 0.05)
				(type solid)
			)
			(fill no)
			(layer "F.CrtYd")
		)
		(fp_rect
			(start -0.8 -0.45)
			(end 0.8 0.45)
			(stroke
				(width 0.15)
				(type solid)
			)
			(fill no)
			(layer "F.Fab")
		)
		(fp_text user "License: Apache-2.0"
			(at -1.682 5.895 270)
			(layer "F.Fab")
			(effects
				(font
					(size 0.7 0.7)
					(thickness 0.15)
				)
				(justify left bottom)
			)
		)
		(fp_text user "Author: Antmicro"
			(at -1.682 4.894 270)
			(layer "F.Fab")
			(effects
				(font
					(size 0.7 0.7)
					(thickness 0.15)
				)
				(justify left bottom)
			)
		)
		(fp_text user "${REFERENCE}"
			(at -1.682 3.895 270)
			(layer "F.Fab")
			(effects
				(font
					(size 0.7 0.7)
					(thickness 0.15)
				)
				(justify left bottom)
			)
		)
		(pad "1" smd roundrect
			(at -0.7 0 270)
			(size 0.8 1.1)
			(layers "F.Cu" "F.Mask" "F.Paste")
			(roundrect_rratio 0.2)
			(net 23 "GND")
			(pintype "passive")
		)
		(pad "2" smd roundrect
			(at 0.7 0 270)
			(size 0.8 1.1)
			(layers "F.Cu" "F.Mask" "F.Paste")
			(roundrect_rratio 0.2)
			(net 9 "VCCD")
			(pintype "passive")
		)
	)
	(footprint "antmicro-footprints:R_0402_1005Metric"
		(layer "F.Cu")
		(at 158 46.3 90)
		(descr "Resistor SMD 0402")
		(tags "resistor SMD 0402")
		(property "Reference" "R228"
			(at -1.9 6.3 90)
			(layer "F.SilkS")
			(effects
				(font
					(size 0.7 0.7)
					(thickness 0.15)
				)
				(justify left bottom)
			)
		)
		(property "Value" "R_499k_0402"
			(at -1.011843 1.772047 90)
			(layer "F.Fab")
			(effects
				(font
					(size 0.7 0.7)
					(thickness 0.15)
				)
				(justify left bottom)
			)
		)
		(property "Datasheet" "https://www.mouser.com/datasheet/2/54/cr-1858361.pdf"
			(at 0 0 90)
			(layer "F.Fab")
			(hide yes)
			(effects
				(font
					(size 1.27 1.27)
					(thickness 0.15)
				)
			)
		)
		(property "Description" "SMD Chip Resistor, 499 kohm, ± 1%, 63 mW, 0402 [1005 Metric], Thick Film, General Purpose"
			(at 0 0 90)
			(layer "F.Fab")
			(hide yes)
			(effects
				(font
					(size 1.27 1.27)
					(thickness 0.15)
				)
			)
		)
		(property "MPN" "CR0402-FX-4993GLF"
			(at 0 0 90)
			(unlocked yes)
			(layer "F.Fab")
			(hide yes)
			(effects
				(font
					(size 1 1)
					(thickness 0.15)
				)
			)
		)
		(property "Manufacturer" "Bourns"
			(at 0 0 90)
			(unlocked yes)
			(layer "F.Fab")
			(hide yes)
			(effects
				(font
					(size 1 1)
					(thickness 0.15)
				)
			)
		)
		(property "License" "Apache-2.0"
			(at 0 0 90)
			(unlocked yes)
			(layer "F.Fab")
			(hide yes)
			(effects
				(font
					(size 1 1)
					(thickness 0.15)
				)
			)
		)
		(property "Author" "Antmicro"
			(at 0 0 90)
			(unlocked yes)
			(layer "F.Fab")
			(hide yes)
			(effects
				(font
					(size 1 1)
					(thickness 0.15)
				)
			)
		)
		(property "Val" "499k"
			(at 0 0 90)
			(unlocked yes)
			(layer "F.Fab")
			(hide yes)
			(effects
				(font
					(size 1 1)
					(thickness 0.15)
				)
			)
		)
		(property "Tolerance" "1%"
			(at 0 0 90)
			(unlocked yes)
			(layer "F.Fab")
			(hide yes)
			(effects
				(font
					(size 1 1)
					(thickness 0.15)
				)
			)
		)
		(sheetname "/Power input/")
		(sheetfile "power_input.kicad_sch")
		(attr smd dnp)
		(fp_rect
			(start -0.925 -0.47)
			(end 0.925 0.47)
			(stroke
				(width 0.05)
				(type default)
			)
			(fill no)
			(layer "F.CrtYd")
		)
		(fp_rect
			(start -0.5 -0.25)
			(end 0.5 0.25)
			(stroke
				(width 0.15)
				(type solid)
			)
			(fill no)
			(layer "F.Fab")
		)
		(fp_text user "${REFERENCE}"
			(at -0.95 3.168 90)
			(layer "F.Fab")
			(effects
				(font
					(size 0.7 0.7)
					(thickness 0.15)
				)
				(justify left bottom)
			)
		)
		(fp_text user "License: Apache-2.0"
			(at -0.95 5.169 90)
			(layer "F.Fab")
			(effects
				(font
					(size 0.7 0.7)
					(thickness 0.15)
				)
				(justify left bottom)
			)
		)
		(fp_text user "Author: Antmicro"
			(at -0.95 4.169 90)
			(layer "F.Fab")
			(effects
				(font
					(size 0.7 0.7)
					(thickness 0.15)
				)
				(justify left bottom)
			)
		)
		(pad "1" smd roundrect
			(at -0.48 0 90)
			(size 0.59 0.64)
			(layers "F.Cu" "F.Mask" "F.Paste")
			(roundrect_rratio 0.25)
			(net 389 "/Power input/5V_MODE1")
			(pintype "passive")
		)
		(pad "2" smd roundrect
			(at 0.48 0 90)
			(size 0.59 0.64)
			(layers "F.Cu" "F.Mask" "F.Paste")
			(roundrect_rratio 0.25)
			(net 345 "/Power input/5V_VDD")
			(pintype "passive")
		)
	)
	(footprint "antmicro-footprints:R_0402_1005Metric"
		(layer "F.Cu")
		(at 170.855 79.361 180)
		(descr "Resistor SMD 0402")
		(tags "resistor SMD 0402")
		(property "Reference" "R172"
			(at 1.655 -1.639 180)
			(layer "F.SilkS")
			(effects
				(font
					(size 0.7 0.7)
					(thickness 0.15)
				)
				(justify left bottom)
			)
		)
		(property "Value" "R_2k_0402"
			(at -1.011843 1.772047 180)
			(layer "F.Fab")
			(effects
				(font
					(size 0.7 0.7)
					(thickness 0.15)
				)
				(justify left bottom)
			)
		)
		(property "Datasheet" "https://www.bourns.com/docs/product-datasheets/cr.pdf"
			(at 0 0 180)
			(layer "F.Fab")
			(hide yes)
			(effects
				(font
					(size 1.27 1.27)
					(thickness 0.15)
				)
			)
		)
		(property "Description" "SMD Chip Resistor, 2 kohm, ± 1%, 62.5 mW, 0402 [1005 Metric], Thick Film, General Purpose"
			(at 0 0 180)
			(layer "F.Fab")
			(hide yes)
			(effects
				(font
					(size 1.27 1.27)
					(thickness 0.15)
				)
			)
		)
		(property "MPN" "CR0402-FX-2001GLF"
			(at 0 0 180)
			(unlocked yes)
			(layer "F.Fab")
			(hide yes)
			(effects
				(font
					(size 1 1)
					(thickness 0.15)
				)
			)
		)
		(property "Manufacturer" "Bourns"
			(at 0 0 180)
			(unlocked yes)
			(layer "F.Fab")
			(hide yes)
			(effects
				(font
					(size 1 1)
					(thickness 0.15)
				)
			)
		)
		(property "License" "Apache-2.0"
			(at 0 0 180)
			(unlocked yes)
			(layer "F.Fab")
			(hide yes)
			(effects
				(font
					(size 1 1)
					(thickness 0.15)
				)
			)
		)
		(property "Author" "Antmicro"
			(at 0 0 180)
			(unlocked yes)
			(layer "F.Fab")
			(hide yes)
			(effects
				(font
					(size 1 1)
					(thickness 0.15)
				)
			)
		)
		(property "Val" "2k"
			(at 0 0 180)
			(unlocked yes)
			(layer "F.Fab")
			(hide yes)
			(effects
				(font
					(size 1 1)
					(thickness 0.15)
				)
			)
		)
		(property "Tolerance" "1%"
			(at 0 0 180)
			(unlocked yes)
			(layer "F.Fab")
			(hide yes)
			(effects
				(font
					(size 1 1)
					(thickness 0.15)
				)
			)
		)
		(sheetname "/X710-AT2 Misc/")
		(sheetfile "x710-at2-mics.kicad_sch")
		(attr smd)
		(fp_rect
			(start -0.925 -0.47)
			(end 0.925 0.47)
			(stroke
				(width 0.05)
				(type default)
			)
			(fill no)
			(layer "F.CrtYd")
		)
		(fp_rect
			(start -0.5 -0.25)
			(end 0.5 0.25)
			(stroke
				(width 0.15)
				(type solid)
			)
			(fill no)
			(layer "F.Fab")
		)
		(fp_text user "License: Apache-2.0"
			(at -0.95 5.169 180)
			(layer "F.Fab")
			(effects
				(font
					(size 0.7 0.7)
					(thickness 0.15)
				)
				(justify left bottom)
			)
		)
		(fp_text user "Author: Antmicro"
			(at -0.95 4.169 180)
			(layer "F.Fab")
			(effects
				(font
					(size 0.7 0.7)
					(thickness 0.15)
				)
				(justify left bottom)
			)
		)
		(fp_text user "${REFERENCE}"
			(at -0.95 3.168 180)
			(layer "F.Fab")
			(effects
				(font
					(size 0.7 0.7)
					(thickness 0.15)
				)
				(justify left bottom)
			)
		)
		(pad "1" smd roundrect
			(at -0.48 0 180)
			(size 0.59 0.64)
			(layers "F.Cu" "F.Mask" "F.Paste")
			(roundrect_rratio 0.25)
			(net 147 "/X710-AT2 Misc/MDIO.MDIO")
			(pintype "passive")
		)
		(pad "2" smd roundrect
			(at 0.48 0 180)
			(size 0.59 0.64)
			(layers "F.Cu" "F.Mask" "F.Paste")
			(roundrect_rratio 0.25)
			(net 18 "+1V88")
			(pintype "passive")
		)
	)
	(footprint "antmicro-footprints:C_0603_1608Metric_EIA"
		(layer "F.Cu")
		(at 162.6 113)
		(descr "Capacitor SMD 0603, IPC-7351 Density Level A")
		(tags "Capacitor 0603")
		(property "Reference" "C112"
			(at 12.450003 16.799998 0)
			(layer "F.SilkS")
			(effects
				(font
					(size 0.7 0.7)
					(thickness 0.15)
				)
			)
		)
		(property "Value" "C_22u_16V_0603"
			(at -1.42757 1.770288 0)
			(layer "F.Fab")
			(effects
				(font
					(size 0.7 0.7)
					(thickness 0.15)
				)
				(justify left bottom)
			)
		)
		(property "Datasheet" "https://product.samsungsem.com/mlcc/CL10A226MO7JZN.do"
			(at 0 0 0)
			(layer "F.Fab")
			(hide yes)
			(effects
				(font
					(size 1.27 1.27)
					(thickness 0.15)
				)
			)
		)
		(property "Description" "SMD Multilayer Ceramic Capacitor"
			(at 0 0 0)
			(layer "F.Fab")
			(hide yes)
			(effects
				(font
					(size 1.27 1.27)
					(thickness 0.15)
				)
			)
		)
		(property "MPN" "CL10A226MO7JZNC"
			(at 0 0 0)
			(unlocked yes)
			(layer "F.Fab")
			(hide yes)
			(effects
				(font
					(size 1 1)
					(thickness 0.15)
				)
			)
		)
		(property "Manufacturer" "Samsung Electro-Mechanics"
			(at 0 0 0)
			(unlocked yes)
			(layer "F.Fab")
			(hide yes)
			(effects
				(font
					(size 1 1)
					(thickness 0.15)
				)
			)
		)
		(property "License" "Apache-2.0"
			(at 0 0 0)
			(unlocked yes)
			(layer "F.Fab")
			(hide yes)
			(effects
				(font
					(size 1 1)
					(thickness 0.15)
				)
			)
		)
		(property "Author" "Antmicro"
			(at 0 0 0)
			(unlocked yes)
			(layer "F.Fab")
			(hide yes)
			(effects
				(font
					(size 1 1)
					(thickness 0.15)
				)
			)
		)
		(property "Val" "22u"
			(at 0 0 0)
			(unlocked yes)
			(layer "F.Fab")
			(hide yes)
			(effects
				(font
					(size 1 1)
					(thickness 0.15)
				)
			)
		)
		(property "Voltage" "16V"
			(at 0 0 0)
			(unlocked yes)
			(layer "F.Fab")
			(hide yes)
			(effects
				(font
					(size 1 1)
					(thickness 0.15)
				)
			)
		)
		(property "Dielectric" ""
			(at 0 0 0)
			(unlocked yes)
			(layer "F.Fab")
			(hide yes)
			(effects
				(font
					(size 1 1)
					(thickness 0.15)
				)
			)
		)
		(sheetname "/X710 DCDC converters/")
		(sheetfile "DCDC_converters_X710.kicad_sch")
		(attr smd)
		(fp_line
			(start -0.15 -0.55)
			(end 0.15 -0.55)
			(stroke
				(width 0.15)
				(type solid)
			)
			(layer "F.SilkS")
		)
		(fp_line
			(start -0.15 0.55)
			(end 0.15 0.55)
			(stroke
				(width 0.15)
				(type solid)
			)
			(layer "F.SilkS")
		)
		(fp_rect
			(start -1.25 -0.65)
			(end 1.25 0.65)
			(stroke
				(width 0.05)
				(type solid)
			)
			(fill no)
			(layer "F.CrtYd")
		)
		(fp_rect
			(start -0.8 -0.45)
			(end 0.8 0.45)
			(stroke
				(width 0.15)
				(type solid)
			)
			(fill no)
			(layer "F.Fab")
		)
		(fp_text user "License: Apache-2.0"
			(at -1.682 5.895 0)
			(layer "F.Fab")
			(effects
				(font
					(size 0.7 0.7)
					(thickness 0.15)
				)
				(justify left bottom)
			)
		)
		(fp_text user "${REFERENCE}"
			(at -1.682 3.895 0)
			(layer "F.Fab")
			(effects
				(font
					(size 0.7 0.7)
					(thickness 0.15)
				)
				(justify left bottom)
			)
		)
		(fp_text user "Author: Antmicro"
			(at -1.682 4.894 0)
			(layer "F.Fab")
			(effects
				(font
					(size 0.7 0.7)
					(thickness 0.15)
				)
				(justify left bottom)
			)
		)
		(pad "1" smd roundrect
			(at -0.7 0)
			(size 0.8 1.1)
			(layers "F.Cu" "F.Mask" "F.Paste")
			(roundrect_rratio 0.2)
			(net 23 "GND")
			(pintype "passive")
		)
		(pad "2" smd roundrect
			(at 0.7 0)
			(size 0.8 1.1)
			(layers "F.Cu" "F.Mask" "F.Paste")
			(roundrect_rratio 0.2)
			(net 40 "+5V")
			(pintype "passive")
		)
	)
)
